(kicad_pcb
	(version 20260206)
	(generator "pcbnew")
	(generator_version "10.0")
	(general
		(thickness 1.6)
		(legacy_teardrops no)
	)
	(paper "A4")
	(title_block
		(title "04192023_DAF0TMB3IC0_F0TG_MB_C_brd_V02_OCP.brd")
		(comment 1 "Grand Teton / footprints 2170-2173 of 8354")
	)
	(layers
		(0 "F.Cu" signal "TOP")
		(4 "In1.Cu" signal "GND")
		(6 "In2.Cu" signal "IN1")
		(8 "In3.Cu" signal "GND1")
		(10 "In4.Cu" signal "IN2")
		(12 "In5.Cu" signal "GND2")
		(14 "In6.Cu" signal "IN3")
		(16 "In7.Cu" signal "GND3")
		(18 "In8.Cu" signal "VCC")
		(20 "In9.Cu" signal "VCC1")
		(22 "In10.Cu" signal "GND4")
		(24 "In11.Cu" signal "IN4")
		(26 "In12.Cu" signal "GND5")
		(28 "In13.Cu" signal "IN5")
		(30 "In14.Cu" signal "GND6")
		(32 "In15.Cu" signal "IN6")
		(34 "In16.Cu" signal "GND7")
		(2 "B.Cu" signal "BOTTOM")
		(9 "F.Adhes" user "F.Adhesive")
		(11 "B.Adhes" user "B.Adhesive")
		(13 "F.Paste" user "Package Geometry/Pastemask Top")
		(15 "B.Paste" user "Package Geometry/Pastemask Bottom")
		(5 "F.SilkS" user "Ref Des/Silkscreen Top")
		(7 "B.SilkS" user "Ref Des/Silkscreen Bottom")
		(1 "F.Mask" user "Board Geometry/Soldermask Top")
		(3 "B.Mask" user "Board Geometry/Soldermask Bottom")
		(17 "Dwgs.User" user "User.Drawings")
		(19 "Cmts.User" user "User.Comments")
		(21 "Eco1.User" user "User.Eco1")
		(23 "Eco2.User" user "User.Eco2")
		(25 "Edge.Cuts" user "Board Geometry/Outline")
		(27 "Margin" user)
		(31 "F.CrtYd" user "Package Geometry/Place Bound Top")
		(29 "B.CrtYd" user "Package Geometry/Place Bound Bottom")
		(35 "F.Fab" user "Ref Des/Assembly Top")
		(33 "B.Fab" user "Ref Des/Assembly Bottom")
	)
	(footprint ""
		(layer "F.Cu")
		(at 285.881064 -418.323014)
		(property "Reference" "U314"
			(at -0.34671 3.762248 0)
			(unlocked yes)
			(layer "F.SilkS")
			(effects
				(font
					(size 0.7874 0.5842)
					(thickness 0.1524)
				)
			)
		)
		(property "Value" ""
			(at 0 0 0)
			(layer "F.Fab")
			(effects
				(font
					(size 1.27 1.27)
				)
			)
		)
		(duplicate_pad_numbers_are_jumpers no)
		(fp_line
			(start -2.500122 -2.500122)
			(end -2.500122 -2.01676)
			(stroke
				(width 0.1524)
				(type default)
			)
			(layer "F.SilkS")
		)
		(fp_line
			(start -2.500122 2.01676)
			(end -2.500122 2.500122)
			(stroke
				(width 0.1524)
				(type default)
			)
			(layer "F.SilkS")
		)
		(fp_line
			(start -2.500122 2.500122)
			(end -2.01676 2.500122)
			(stroke
				(width 0.1524)
				(type default)
			)
			(layer "F.SilkS")
		)
		(fp_line
			(start -2.01676 -2.500122)
			(end -2.500122 -2.500122)
			(stroke
				(width 0.1524)
				(type default)
			)
			(layer "F.SilkS")
		)
		(fp_line
			(start 2.01676 2.500122)
			(end 2.500122 2.500122)
			(stroke
				(width 0.1524)
				(type default)
			)
			(layer "F.SilkS")
		)
		(fp_line
			(start 2.500122 -2.500122)
			(end 2.01676 -2.500122)
			(stroke
				(width 0.1524)
				(type default)
			)
			(layer "F.SilkS")
		)
		(fp_line
			(start 2.500122 -2.01676)
			(end 2.500122 -2.500122)
			(stroke
				(width 0.1524)
				(type default)
			)
			(layer "F.SilkS")
		)
		(fp_line
			(start 2.500122 2.500122)
			(end 2.500122 2.01676)
			(stroke
				(width 0.1524)
				(type default)
			)
			(layer "F.SilkS")
		)
		(fp_poly
			(pts
				(xy -4.299458 -1.75006) (xy -5.494782 -1.152398) (xy -5.494782 -2.347722)
			)
			(stroke
				(width 0)
				(type default)
			)
			(fill yes)
			(layer "F.SilkS")
		)
		(fp_line
			(start -2.500122 -2.500122)
			(end -2.500122 2.500122)
			(stroke
				(width 0.1)
				(type default)
			)
			(layer "F.Fab")
		)
		(fp_line
			(start -2.500122 2.500122)
			(end 2.500122 2.500122)
			(stroke
				(width 0.1)
				(type default)
			)
			(layer "F.Fab")
		)
		(fp_line
			(start 2.500122 -2.500122)
			(end -2.500122 -2.500122)
			(stroke
				(width 0.1)
				(type default)
			)
			(layer "F.Fab")
		)
		(fp_line
			(start 2.500122 2.500122)
			(end 2.500122 -2.500122)
			(stroke
				(width 0.1)
				(type default)
			)
			(layer "F.Fab")
		)
		(fp_poly
			(pts
				(xy -3.044698 -1.75006) (xy -4.240022 -1.152398) (xy -4.240022 -2.347722)
			)
			(stroke
				(width 0)
				(type default)
			)
			(fill yes)
			(layer "F.Fab")
		)
		(pad "1" smd rect
			(at -2.3749 -1.75006 270)
			(size 0.254 0.5588)
			(layers "F.Cu" "F.Mask" "F.Paste")
			(net "FM_9ZXL045_P0_DEV_EN")
		)
		(pad "2" smd rect
			(at -2.3749 -1.249934 270)
			(size 0.254 0.5588)
			(layers "F.Cu" "F.Mask" "F.Paste")
			(net "P3V3_9ZXL045_P0_VDDR")
		)
		(pad "3" smd rect
			(at -2.3749 -0.750062 270)
			(size 0.254 0.5588)
			(layers "F.Cu" "F.Mask" "F.Paste")
			(net "CLK_100M_CPU0_CLK13_DP")
		)
		(pad "4" smd rect
			(at -2.3749 -0.249936 270)
			(size 0.254 0.5588)
			(layers "F.Cu" "F.Mask" "F.Paste")
			(net "CLK_100M_CPU0_CLK13_DN")
		)
		(pad "5" smd rect
			(at -2.3749 0.249936 270)
			(size 0.254 0.5588)
			(layers "F.Cu" "F.Mask" "F.Paste")
			(net "CLK_9ZXL045_P0_SADR0")
		)
		(pad "6" smd rect
			(at -2.3749 0.750062 270)
			(size 0.254 0.5588)
			(layers "F.Cu" "F.Mask" "F.Paste")
			(net "SMB_9ZXL045_P0_SDA")
		)
		(pad "7" smd rect
			(at -2.3749 1.249934 270)
			(size 0.254 0.5588)
			(layers "F.Cu" "F.Mask" "F.Paste")
			(net "SMB_9ZXL045_P0_SCL")
		)
		(pad "8" smd rect
			(at -2.3749 1.75006 270)
			(size 0.254 0.5588)
			(layers "F.Cu" "F.Mask" "F.Paste")
			(net "NC_U314_FBOUT_N")
		)
		(pad "9" smd rect
			(at -1.75006 2.3749)
			(size 0.254 0.5588)
			(layers "F.Cu" "F.Mask" "F.Paste")
			(net "NC_U314_FBOUT")
		)
		(pad "10" smd rect
			(at -1.249934 2.3749)
			(size 0.254 0.5588)
			(layers "F.Cu" "F.Mask" "F.Paste")
			(net "NC_U314_NC0")
		)
		(pad "11" smd rect
			(at -0.750062 2.3749)
			(size 0.254 0.5588)
			(layers "F.Cu" "F.Mask" "F.Paste")
			(net "NC_U314_NC1")
		)
		(pad "12" smd rect
			(at -0.249936 2.3749)
			(size 0.254 0.5588)
			(layers "F.Cu" "F.Mask" "F.Paste")
			(net "P3V3_9ZXL045_P0_VDD")
		)
		(pad "13" smd rect
			(at 0.249936 2.3749)
			(size 0.254 0.5588)
			(layers "F.Cu" "F.Mask" "F.Paste")
			(net "CLK_100M_RETIMER_CPU0_P0_R_DP")
		)
		(pad "14" smd rect
			(at 0.750062 2.3749)
			(size 0.254 0.5588)
			(layers "F.Cu" "F.Mask" "F.Paste")
			(net "CLK_100M_RETIMER_CPU0_P0_R_DN")
		)
		(pad "15" smd rect
			(at 1.249934 2.3749)
			(size 0.254 0.5588)
			(layers "F.Cu" "F.Mask" "F.Paste")
			(net "FM_9ZXL045_P0_0_OE_N")
		)
		(pad "16" smd rect
			(at 1.75006 2.3749)
			(size 0.254 0.5588)
			(layers "F.Cu" "F.Mask" "F.Paste")
			(net "P3V3_9ZXL045_P0_VDD")
		)
		(pad "17" smd rect
			(at 2.3749 1.75006 90)
			(size 0.254 0.5588)
			(layers "F.Cu" "F.Mask" "F.Paste")
			(net "NC_U314_NC2")
		)
		(pad "18" smd rect
			(at 2.3749 1.249934 90)
			(size 0.254 0.5588)
			(layers "F.Cu" "F.Mask" "F.Paste")
			(net "FM_9ZXL045_P0_1_OE_N")
		)
		(pad "19" smd rect
			(at 2.3749 0.750062 90)
			(size 0.254 0.5588)
			(layers "F.Cu" "F.Mask" "F.Paste")
			(net "CLK_100M_RETIMER_CPU0_P1_R_DP")
		)
		(pad "20" smd rect
			(at 2.3749 0.249936 90)
			(size 0.254 0.5588)
			(layers "F.Cu" "F.Mask" "F.Paste")
			(net "CLK_100M_RETIMER_CPU0_P1_R_DN")
		)
		(pad "21" smd rect
			(at 2.3749 -0.249936 90)
			(size 0.254 0.5588)
			(layers "F.Cu" "F.Mask" "F.Paste")
			(net "P3V3_9ZXL045_P0_VDD")
		)
		(pad "22" smd rect
			(at 2.3749 -0.750062 90)
			(size 0.254 0.5588)
			(layers "F.Cu" "F.Mask" "F.Paste")
			(net "CLK_100M_RETIMER_CPU0_P2_R_DP")
		)
		(pad "23" smd rect
			(at 2.3749 -1.249934 90)
			(size 0.254 0.5588)
			(layers "F.Cu" "F.Mask" "F.Paste")
			(net "CLK_100M_RETIMER_CPU0_P2_R_DN")
		)
		(pad "24" smd rect
			(at 2.3749 -1.75006 90)
			(size 0.254 0.5588)
			(layers "F.Cu" "F.Mask" "F.Paste")
			(net "FM_9ZXL045_P0_2_OE_N")
		)
		(pad "25" smd rect
			(at 1.75006 -2.3749 180)
			(size 0.254 0.5588)
			(layers "F.Cu" "F.Mask" "F.Paste")
			(net "P3V3_9ZXL045_P0_VDD")
		)
		(pad "26" smd rect
			(at 1.249934 -2.3749 180)
			(size 0.254 0.5588)
			(layers "F.Cu" "F.Mask" "F.Paste")
			(net "FM_9ZXL045_P0_3_OE_N")
		)
		(pad "27" smd rect
			(at 0.750062 -2.3749 180)
			(size 0.254 0.5588)
			(layers "F.Cu" "F.Mask" "F.Paste")
			(net "CLK_100M_RETIMER_CPU0_P3_R_DP")
		)
		(pad "28" smd rect
			(at 0.249936 -2.3749 180)
			(size 0.254 0.5588)
			(layers "F.Cu" "F.Mask" "F.Paste")
			(net "CLK_100M_RETIMER_CPU0_P3_R_DN")
		)
		(pad "29" smd rect
			(at -0.249936 -2.3749 180)
			(size 0.254 0.5588)
			(layers "F.Cu" "F.Mask" "F.Paste")
			(net "P3V3_9ZXL045_P0_VDD")
		)
		(pad "30" smd rect
			(at -0.750062 -2.3749 180)
			(size 0.254 0.5588)
			(layers "F.Cu" "F.Mask" "F.Paste")
			(net "NC_U314_NC3")
		)
		(pad "31" smd rect
			(at -1.249934 -2.3749 180)
			(size 0.254 0.5588)
			(layers "F.Cu" "F.Mask" "F.Paste")
			(net "P3V3_9ZXL045_P0_VDDA")
		)
		(pad "32" smd rect
			(at -1.75006 -2.3749 180)
			(size 0.254 0.5588)
			(layers "F.Cu" "F.Mask" "F.Paste")
			(net "CLK_9ZXL045_P0_HIBW")
		)
		(pad "33" smd rect
			(at 0 0)
			(size 3.1496 3.1496)
			(layers "F.Cu" "F.Mask" "F.Paste")
			(net "GND")
		)
		(zone
			(layer "F.Cu")
			(hatch none 0.5)
			(connect_pads
				(clearance 0)
			)
			(min_thickness 0.25)
			(keepout
				(tracks not_allowed)
				(vias allowed)
				(pads allowed)
				(copperpour not_allowed)
				(footprints allowed)
			)
			(placement
				(enabled no)
				(sheetname "")
			)
			(fill
				(thermal_gap 0.5)
				(thermal_bridge_width 0.5)
				(island_removal_mode 0)
			)
			(polygon
				(pts
					(xy 283.836364 -416.278314) (xy 283.836364 -419.547548) (xy 284.255464 -419.547548) (xy 284.255464 -416.697414)
					(xy 287.506664 -416.697414) (xy 287.506664 -419.948614) (xy 284.255464 -419.948614) (xy 284.255464 -419.572948)
					(xy 283.836364 -419.572948) (xy 283.836364 -420.367714) (xy 287.925764 -420.367714) (xy 287.925764 -416.278314)
				)
			)
		)
	)
	(footprint ""
		(layer "F.Cu")
		(at 372.937278 -141.472158)
		(property "Reference" "R8317"
			(at 0 0 0)
			(layer "F.SilkS")
			(hide yes)
			(effects
				(font
					(size 1.27 1.27)
				)
			)
		)
		(property "Value" ""
			(at 0 0 0)
			(layer "F.Fab")
			(effects
				(font
					(size 1.27 1.27)
				)
			)
		)
		(duplicate_pad_numbers_are_jumpers no)
		(fp_line
			(start -0.7874 -0.4064)
			(end 0.7874 -0.4064)
			(stroke
				(width 0.1524)
				(type default)
			)
			(layer "F.SilkS")
		)
		(fp_line
			(start -0.7874 0.4064)
			(end -0.7874 -0.4064)
			(stroke
				(width 0.1524)
				(type default)
			)
			(layer "F.SilkS")
		)
		(fp_line
			(start 0.7874 -0.4064)
			(end 0.7874 0.4064)
			(stroke
				(width 0.1524)
				(type default)
			)
			(layer "F.SilkS")
		)
		(fp_line
			(start 0.7874 0.4064)
			(end -0.7874 0.4064)
			(stroke
				(width 0.1524)
				(type default)
			)
			(layer "F.SilkS")
		)
		(fp_line
			(start -0.67945 -0.305054)
			(end -0.12065 -0.305054)
			(stroke
				(width 0.1)
				(type default)
			)
			(layer "F.Fab")
		)
		(fp_line
			(start -0.67945 0.3048)
			(end -0.67945 -0.305054)
			(stroke
				(width 0.1)
				(type default)
			)
			(layer "F.Fab")
		)
		(fp_line
			(start -0.12065 -0.305054)
			(end -0.12065 -0.2794)
			(stroke
				(width 0.1)
				(type default)
			)
			(layer "F.Fab")
		)
		(fp_line
			(start -0.12065 -0.2794)
			(end 0.12065 -0.2794)
			(stroke
				(width 0.1)
				(type default)
			)
			(layer "F.Fab")
		)
		(fp_line
			(start -0.12065 0.2794)
			(end -0.12065 0.3048)
			(stroke
				(width 0.1)
				(type default)
			)
			(layer "F.Fab")
		)
		(fp_line
			(start -0.12065 0.3048)
			(end -0.67945 0.3048)
			(stroke
				(width 0.1)
				(type default)
			)
			(layer "F.Fab")
		)
		(fp_line
			(start 0.120396 0.2794)
			(end -0.12065 0.2794)
			(stroke
				(width 0.1)
				(type default)
			)
			(layer "F.Fab")
		)
		(fp_line
			(start 0.120396 0.3048)
			(end 0.120396 0.2794)
			(stroke
				(width 0.1)
				(type default)
			)
			(layer "F.Fab")
		)
		(fp_line
			(start 0.12065 -0.3048)
			(end 0.67945 -0.3048)
			(stroke
				(width 0.1)
				(type default)
			)
			(layer "F.Fab")
		)
		(fp_line
			(start 0.12065 -0.2794)
			(end 0.12065 -0.3048)
			(stroke
				(width 0.1)
				(type default)
			)
			(layer "F.Fab")
		)
		(fp_line
			(start 0.67945 -0.3048)
			(end 0.67945 0.3048)
			(stroke
				(width 0.1)
				(type default)
			)
			(layer "F.Fab")
		)
		(fp_line
			(start 0.67945 0.3048)
			(end 0.120396 0.3048)
			(stroke
				(width 0.1)
				(type default)
			)
			(layer "F.Fab")
		)
		(pad "1" smd circle
			(at -0.40005 0)
			(size 0 0)
			(layers "F.Cu" "F.Mask" "F.Paste")
			(net "PVDD18_S5_P0")
		)
		(pad "2" smd circle
			(at 0.40005 0)
			(size 0 0)
			(layers "F.Cu" "F.Mask" "F.Paste")
			(net "PVDDCR_CPU0_P0_RESET_N_R")
		)
	)
	(footprint ""
		(layer "F.Cu")
		(at 336.844894 -339.625432 -90)
		(property "Reference" "PC92"
			(at 0 0 270)
			(layer "F.SilkS")
			(hide yes)
			(effects
				(font
					(size 1.27 1.27)
				)
			)
		)
		(property "Value" ""
			(at 0 0 270)
			(layer "F.Fab")
			(effects
				(font
					(size 1.27 1.27)
				)
			)
		)
		(duplicate_pad_numbers_are_jumpers no)
		(fp_line
			(start -0.7874 0.4064)
			(end -0.7874 -0.4064)
			(stroke
				(width 0.1524)
				(type default)
			)
			(layer "F.SilkS")
		)
		(fp_line
			(start 0.7874 0.4064)
			(end -0.7874 0.4064)
			(stroke
				(width 0.1524)
				(type default)
			)
			(layer "F.SilkS")
		)
		(fp_line
			(start -0.7874 -0.4064)
			(end 0.7874 -0.4064)
			(stroke
				(width 0.1524)
				(type default)
			)
			(layer "F.SilkS")
		)
		(fp_line
			(start 0.7874 -0.4064)
			(end 0.7874 0.4064)
			(stroke
				(width 0.1524)
				(type default)
			)
			(layer "F.SilkS")
		)
		(fp_line
			(start -0.67945 0.3048)
			(end -0.67945 -0.305054)
			(stroke
				(width 0.1)
				(type default)
			)
			(layer "F.Fab")
		)
		(fp_line
			(start -0.12065 0.3048)
			(end -0.67945 0.3048)
			(stroke
				(width 0.1)
				(type default)
			)
			(layer "F.Fab")
		)
		(fp_line
			(start 0.120396 0.3048)
			(end 0.120396 0.2794)
			(stroke
				(width 0.1)
				(type default)
			)
			(layer "F.Fab")
		)
		(fp_line
			(start 0.67945 0.3048)
			(end 0.120396 0.3048)
			(stroke
				(width 0.1)
				(type default)
			)
			(layer "F.Fab")
		)
		(fp_line
			(start -0.12065 0.2794)
			(end -0.12065 0.3048)
			(stroke
				(width 0.1)
				(type default)
			)
			(layer "F.Fab")
		)
		(fp_line
			(start 0.120396 0.2794)
			(end -0.12065 0.2794)
			(stroke
				(width 0.1)
				(type default)
			)
			(layer "F.Fab")
		)
		(fp_line
			(start -0.12065 -0.2794)
			(end 0.12065 -0.2794)
			(stroke
				(width 0.1)
				(type default)
			)
			(layer "F.Fab")
		)
		(fp_line
			(start 0.12065 -0.2794)
			(end 0.12065 -0.3048)
			(stroke
				(width 0.1)
				(type default)
			)
			(layer "F.Fab")
		)
		(fp_line
			(start 0.12065 -0.3048)
			(end 0.67945 -0.3048)
			(stroke
				(width 0.1)
				(type default)
			)
			(layer "F.Fab")
		)
		(fp_line
			(start 0.67945 -0.3048)
			(end 0.67945 0.3048)
			(stroke
				(width 0.1)
				(type default)
			)
			(layer "F.Fab")
		)
		(fp_line
			(start -0.67945 -0.305054)
			(end -0.12065 -0.305054)
			(stroke
				(width 0.1)
				(type default)
			)
			(layer "F.Fab")
		)
		(fp_line
			(start -0.12065 -0.305054)
			(end -0.12065 -0.2794)
			(stroke
				(width 0.1)
				(type default)
			)
			(layer "F.Fab")
		)
		(pad "1" smd circle
			(at -0.40005 0 270)
			(size 0 0)
			(layers "F.Cu" "F.Mask" "F.Paste")
			(net "SW_PVDDCR_CPU1_P0_BOOT1_R")
		)
		(pad "2" smd circle
			(at 0.40005 0 270)
			(size 0 0)
			(layers "F.Cu" "F.Mask" "F.Paste")
			(net "SW_PVDDCR_CPU1_P0_BOOTR1")
		)
	)
	(footprint ""
		(layer "F.Cu")
		(at 39.15029 -425.256706)
		(property "Reference" "C1869"
			(at 0 0 0)
			(layer "F.SilkS")
			(hide yes)
			(effects
				(font
					(size 1.27 1.27)
				)
			)
		)
		(property "Value" ""
			(at 0 0 0)
			(layer "F.Fab")
			(effects
				(font
					(size 1.27 1.27)
				)
			)
		)
		(duplicate_pad_numbers_are_jumpers no)
		(fp_line
			(start -0.7874 -0.4064)
			(end -0.33909 -0.4064)
			(stroke
				(width 0.1524)
				(type default)
			)
			(layer "F.SilkS")
		)
		(fp_line
			(start 0.7874 -0.294894)
			(end 0.7874 0.4064)
			(stroke
				(width 0.1524)
				(type default)
			)
			(layer "F.SilkS")
		)
		(fp_line
			(start 0.7874 0.4064)
			(end -0.7874 0.4064)
			(stroke
				(width 0.1524)
				(type default)
			)
			(layer "F.SilkS")
		)
		(fp_line
			(start -0.6858 -0.3048)
			(end -0.1016 -0.3048)
			(stroke
				(width 0.1)
				(type default)
			)
			(layer "F.Fab")
		)
		(fp_line
			(start -0.6858 0.3048)
			(end -0.6858 -0.3048)
			(stroke
				(width 0.1)
				(type default)
			)
			(layer "F.Fab")
		)
		(fp_line
			(start -0.1016 -0.3048)
			(end -0.1016 -0.2794)
			(stroke
				(width 0.1)
				(type default)
			)
			(layer "F.Fab")
		)
		(fp_line
			(start -0.1016 -0.2794)
			(end 0.1016 -0.2794)
			(stroke
				(width 0.1)
				(type default)
			)
			(layer "F.Fab")
		)
		(fp_line
			(start -0.1016 0.2794)
			(end -0.1016 0.3048)
			(stroke
				(width 0.1)
				(type default)
			)
			(layer "F.Fab")
		)
		(fp_line
			(start -0.1016 0.3048)
			(end -0.6858 0.3048)
			(stroke
				(width 0.1)
				(type default)
			)
			(layer "F.Fab")
		)
		(fp_line
			(start 0.1016 -0.3048)
			(end 0.6858 -0.3048)
			(stroke
				(width 0.1)
				(type default)
			)
			(layer "F.Fab")
		)
		(fp_line
			(start 0.1016 -0.2794)
			(end 0.1016 -0.3048)
			(stroke
				(width 0.1)
				(type default)
			)
			(layer "F.Fab")
		)
		(fp_line
			(start 0.1016 0.2794)
			(end -0.1016 0.2794)
			(stroke
				(width 0.1)
				(type default)
			)
			(layer "F.Fab")
		)
		(fp_line
			(start 0.1016 0.3048)
			(end 0.1016 0.2794)
			(stroke
				(width 0.1)
				(type default)
			)
			(layer "F.Fab")
		)
		(fp_line
			(start 0.6858 -0.3048)
			(end 0.6858 0.3048)
			(stroke
				(width 0.1)
				(type default)
			)
			(layer "F.Fab")
		)
		(fp_line
			(start 0.6858 0.3048)
			(end 0.1016 0.3048)
			(stroke
				(width 0.1)
				(type default)
			)
			(layer "F.Fab")
		)
		(pad "1" smd rect
			(at -0.40005 0 180)
			(size 0.4572 0.508)
			(layers "F.Cu" "F.Mask" "F.Paste")
			(net "P2E_MB_BMC_RX_BUF_C_DN<0>")
		)
		(pad "2" smd rect
			(at 0.40005 0 180)
			(size 0.4572 0.508)
			(layers "F.Cu" "F.Mask" "F.Paste")
			(net "P2E_MB_BMC_RX_BUF_DN<0>")
		)
	)
)
